(kicad_pcb
	(version 20260206)
	(generator "pcbnew")
	(generator_version "10.0")
	(general
		(thickness 1.21888)
		(legacy_teardrops no)
	)
	(paper "A4")
	(title_block
		(title "timecard-v9 — TimeCard-DC-V9_EXP.PcbDoc")
		(comment 1 "Time Appliance Project (Time Card) / footprints 156-158 of 402")
	)
	(layers
		(0 "F.Cu" signal "TOP")
		(4 "In1.Cu" signal "SGND")
		(6 "In2.Cu" signal "IN1")
		(8 "In3.Cu" signal "IN2")
		(10 "In4.Cu" signal "SGND1")
		(2 "B.Cu" signal "BOTTOM")
		(9 "F.Adhes" user "F.Adhesive")
		(11 "B.Adhes" user "B.Adhesive")
		(13 "F.Paste" user "Top Paste")
		(15 "B.Paste" user "Bottom Paste")
		(5 "F.SilkS" user "Top Overlay")
		(7 "B.SilkS" user "Bottom Overlay")
		(1 "F.Mask" user "Top Solder")
		(3 "B.Mask" user "Bottom Solder")
		(17 "Dwgs.User" user "User.Drawings")
		(19 "Cmts.User" user "User.Comments")
		(21 "Eco1.User" user "User.Eco1")
		(23 "Eco2.User" user "User.Eco2")
		(25 "Edge.Cuts" user)
		(27 "Margin" user)
		(31 "F.CrtYd" user "Top Courtyard")
		(29 "B.CrtYd" user "Bottom Courtyard")
		(35 "F.Fab" user "Top Component Center")
		(33 "B.Fab" user "Bottom Component Center")
	)
	(footprint "Vault:FP-MYMGK-12-MFG"
		(layer "F.Cu")
		(at 87.7216 59.3162 90)
		(property "Reference" "U5"
			(at -4.506655 -0.3 180)
			(unlocked yes)
			(layer "F.SilkS")
			(effects
				(font
					(size 0.762 0.762)
					(thickness 0.2286)
				)
				(justify left bottom)
			)
		)
		(property "Value" "DNI_MYMGK00506ERSR"
			(at -27.796575 6.8959 0)
			(unlocked yes)
			(layer "F.SilkS")
			(hide yes)
			(effects
				(font
					(size 0.762 0.762)
					(thickness 0.2286)
				)
				(justify left bottom)
			)
		)
		(sheetname "03-POWER")
		(sheetfile "03-POWER.kicad_sch")
		(duplicate_pad_numbers_are_jumpers no)
		(fp_line
			(start 3.825 -4.575)
			(end 3.825 4.575)
			(stroke
				(width 0.2)
				(type solid)
			)
			(layer "F.SilkS")
		)
		(fp_line
			(start 3.625 -4.575)
			(end 3.825 -4.575)
			(stroke
				(width 0.2)
				(type solid)
			)
			(layer "F.SilkS")
		)
		(fp_line
			(start -0.325 -4.575)
			(end 0.325 -4.575)
			(stroke
				(width 0.2)
				(type solid)
			)
			(layer "F.SilkS")
		)
		(fp_line
			(start -3.825 -4.575)
			(end -3.625 -4.575)
			(stroke
				(width 0.2)
				(type solid)
			)
			(layer "F.SilkS")
		)
		(fp_line
			(start -3.825 -4.575)
			(end -3.825 4.575)
			(stroke
				(width 0.2)
				(type solid)
			)
			(layer "F.SilkS")
		)
		(fp_line
			(start 3.625 4.575)
			(end 3.825 4.575)
			(stroke
				(width 0.2)
				(type solid)
			)
			(layer "F.SilkS")
		)
		(fp_line
			(start -0.325 4.575)
			(end 0.325 4.575)
			(stroke
				(width 0.2)
				(type solid)
			)
			(layer "F.SilkS")
		)
		(fp_line
			(start -3.825 4.575)
			(end -3.625 4.575)
			(stroke
				(width 0.2)
				(type solid)
			)
			(layer "F.SilkS")
		)
		(fp_circle
			(center -4.575 -3.625)
			(end -4.45 -3.625)
			(stroke
				(width 0.25)
				(type solid)
			)
			(fill no)
			(layer "F.SilkS")
		)
		(fp_line
			(start 4.325 -5.075)
			(end 4.325 5.075)
			(stroke
				(width 0.2)
				(type solid)
			)
			(layer "F.CrtYd")
		)
		(fp_line
			(start -4.325 -5.075)
			(end 4.325 -5.075)
			(stroke
				(width 0.2)
				(type solid)
			)
			(layer "F.CrtYd")
		)
		(fp_line
			(start -4.325 -5.075)
			(end -4.325 5.075)
			(stroke
				(width 0.2)
				(type solid)
			)
			(layer "F.CrtYd")
		)
		(fp_line
			(start -4.325 5.075)
			(end 4.325 5.075)
			(stroke
				(width 0.2)
				(type solid)
			)
			(layer "F.CrtYd")
		)
		(fp_line
			(start 4.325 -5.075)
			(end 4.325 5.075)
			(stroke
				(width 0.2)
				(type solid)
			)
			(layer "F.Fab")
		)
		(fp_line
			(start -4.325 -5.075)
			(end 4.325 -5.075)
			(stroke
				(width 0.2)
				(type solid)
			)
			(layer "F.Fab")
		)
		(fp_line
			(start -4.325 -5.075)
			(end -4.325 5.075)
			(stroke
				(width 0.2)
				(type solid)
			)
			(layer "F.Fab")
		)
		(fp_line
			(start 0 -0.5)
			(end 0 0.5)
			(stroke
				(width 0.1)
				(type solid)
			)
			(layer "F.Fab")
		)
		(fp_line
			(start -0.5 0)
			(end 0.5 0)
			(stroke
				(width 0.1)
				(type solid)
			)
			(layer "F.Fab")
		)
		(fp_line
			(start -4.325 5.075)
			(end 4.325 5.075)
			(stroke
				(width 0.2)
				(type solid)
			)
			(layer "F.Fab")
		)
		(fp_text user "${REFERENCE}"
			(at -0.00001 0.09602 90)
			(unlocked yes)
			(layer "F.Fab")
			(effects
				(font
					(face "Arial")
					(size 0.63 0.63)
					(thickness 0.1)
				)
				(justify left bottom)
			)
		)
		(pad "" smd custom
			(at -1.7 -0.75)
			(size 0.000001 0.000001)
			(layers "F.Cu" "F.Mask" "F.Paste")
			(solder_mask_margin 0)
			(solder_paste_margin 0)
			(thermal_bridge_angle 90)
			(options
				(clearance outline)
				(anchor circle)
			)
			(primitives
				(gr_poly
					(pts
						(xy 0 0) (xy 0 -1) (xy -0.9 -1) (xy -0.9 -0.45) (xy -0.45 0)
					)
					(width 0)
					(fill yes)
				)
			)
		)
		(pad "1" smd rect
			(at -2.75 -3.55 90)
			(size 1 1.4)
			(layers "F.Cu" "F.Mask" "F.Paste")
			(net "+12V")
			(solder_mask_margin 0)
			(solder_paste_margin 0)
		)
		(pad "2" smd rect
			(at -1.2 -3.55 90)
			(size 1 1.4)
			(layers "F.Cu" "F.Mask" "F.Paste")
			(net "+12V")
			(solder_mask_margin 0)
			(solder_paste_margin 0)
		)
		(pad "3" smd rect
			(at -2.75 -1.2 90)
			(size 1 0.9)
			(layers "F.Cu" "F.Mask" "F.Paste")
			(net "GND")
			(solder_mask_margin 0)
			(solder_paste_margin 0)
		)
		(pad "4" smd rect
			(at -2.75 0 90)
			(size 1 0.9)
			(layers "F.Cu" "F.Mask" "F.Paste")
			(net "NetR26_2")
			(solder_mask_margin 0)
			(solder_paste_margin 0)
		)
		(pad "5" smd rect
			(at -2.75 1.2 90)
			(size 1 0.9)
			(layers "F.Cu" "F.Mask" "F.Paste")
			(net "P5V_SENSE")
			(solder_mask_margin 0)
			(solder_paste_margin 0)
		)
		(pad "6" smd rect
			(at -2.75 3.55 90)
			(size 1 1.4)
			(layers "F.Cu" "F.Mask" "F.Paste")
			(net "P5V_SENSE")
			(solder_mask_margin 0)
			(solder_paste_margin 0)
		)
		(pad "7" smd rect
			(at -1.2 3.55 90)
			(size 1 1.4)
			(layers "F.Cu" "F.Mask" "F.Paste")
			(net "P5V_SENSE")
			(solder_mask_margin 0)
			(solder_paste_margin 0)
		)
		(pad "8" smd rect
			(at 1.2 3.55 90)
			(size 1 1.4)
			(layers "F.Cu" "F.Mask" "F.Paste")
			(net "GND")
			(solder_mask_margin 0)
			(solder_paste_margin 0)
		)
		(pad "9" smd rect
			(at 2.75 3.55 90)
			(size 1 1.4)
			(layers "F.Cu" "F.Mask" "F.Paste")
			(net "GND")
			(solder_mask_margin 0)
			(solder_paste_margin 0)
		)
		(pad "10" smd rect
			(at 2.75 1.2 90)
			(size 1 0.9)
			(layers "F.Cu" "F.Mask" "F.Paste")
			(net "GND")
			(solder_mask_margin 0)
			(solder_paste_margin 0)
		)
		(pad "11" smd rect
			(at 2.75 0 90)
			(size 1 0.9)
			(layers "F.Cu" "F.Mask" "F.Paste")
			(net "NetR9_2")
			(solder_mask_margin 0)
			(solder_paste_margin 0)
		)
		(pad "12" smd rect
			(at 2.75 -1.2 90)
			(size 1 0.9)
			(layers "F.Cu" "F.Mask" "F.Paste")
			(net "NetR6_2")
			(solder_mask_margin 0)
			(solder_paste_margin 0)
		)
		(pad "13" smd rect
			(at 2.75 -3.55 90)
			(size 1 1.4)
			(layers "F.Cu" "F.Mask" "F.Paste")
			(net "GND")
			(solder_mask_margin 0)
			(solder_paste_margin 0)
		)
		(pad "14" smd rect
			(at 1.2 -3.55 90)
			(size 1 1.4)
			(layers "F.Cu" "F.Mask" "F.Paste")
			(net "GND")
			(solder_mask_margin 0)
			(solder_paste_margin 0)
		)
		(pad "15" smd circle
			(at -1.15563 -1.16197 90)
			(size 0.74127 0.74127)
			(layers "F.Cu" "F.Mask" "F.Paste")
			(net "GND")
			(solder_mask_margin 0)
			(solder_paste_margin 0)
			(thermal_bridge_angle 90)
		)
		(pad "16" smd rect
			(at -1.2 0 90)
			(size 1 0.9)
			(layers "F.Cu" "F.Mask" "F.Paste")
			(net "GND")
			(solder_mask_margin 0)
			(solder_paste_margin 0)
		)
		(pad "17" smd rect
			(at -1.2 1.2 90)
			(size 1 0.9)
			(layers "F.Cu" "F.Mask" "F.Paste")
			(net "GND")
			(solder_mask_margin 0)
			(solder_paste_margin 0)
		)
		(pad "18" smd rect
			(at 0 -1.2 90)
			(size 1 0.9)
			(layers "F.Cu" "F.Mask" "F.Paste")
			(net "GND")
			(solder_mask_margin 0)
			(solder_paste_margin 0)
		)
		(pad "19" smd rect
			(at 0 0 90)
			(size 1 0.9)
			(layers "F.Cu" "F.Mask" "F.Paste")
			(net "GND")
			(solder_mask_margin 0)
			(solder_paste_margin 0)
		)
		(pad "20" smd rect
			(at 0 1.2 90)
			(size 1 0.9)
			(layers "F.Cu" "F.Mask" "F.Paste")
			(net "GND")
			(solder_mask_margin 0)
			(solder_paste_margin 0)
		)
		(pad "21" smd rect
			(at 1.2 -1.2 90)
			(size 1 0.9)
			(layers "F.Cu" "F.Mask" "F.Paste")
			(net "GND")
			(solder_mask_margin 0)
			(solder_paste_margin 0)
		)
		(pad "22" smd rect
			(at 1.2 0 90)
			(size 1 0.9)
			(layers "F.Cu" "F.Mask" "F.Paste")
			(net "GND")
			(solder_mask_margin 0)
			(solder_paste_margin 0)
		)
		(pad "23" smd rect
			(at 1.2 1.2 90)
			(size 1 0.9)
			(layers "F.Cu" "F.Mask" "F.Paste")
			(net "GND")
			(solder_mask_margin 0)
			(solder_paste_margin 0)
		)
	)
	(footprint "Vault:RESC1005X40X25NL10T10"
		(layer "F.Cu")
		(at 171.4216 118.8162 -90)
		(property "Reference" "R120"
			(at 2.7032 -0.045329 270)
			(unlocked yes)
			(layer "F.SilkS")
			(effects
				(font
					(size 0.762 0.762)
					(thickness 0.2032)
				)
			)
		)
		(property "Value" "4.7K_1%_0402"
			(at -2.732271 8.747475 180)
			(unlocked yes)
			(layer "F.SilkS")
			(hide yes)
			(effects
				(font
					(size 0.762 0.762)
					(thickness 0.2032)
				)
			)
		)
		(sheetname "08-DIPSwitches_I2C")
		(sheetfile "08-DIPSwitches_I2C.kicad_sch")
		(duplicate_pad_numbers_are_jumpers no)
		(pad "1" smd rect
			(at -0.425 0)
			(size 0.6 0.65)
			(layers "F.Cu" "F.Mask" "F.Paste")
			(net "MAC_I2C_SCL")
		)
		(pad "2" smd rect
			(at 0.425 0)
			(size 0.6 0.65)
			(layers "F.Cu" "F.Mask" "F.Paste")
			(net "+3.3V")
		)
	)
	(footprint "PI3A412ZHE:ZH16_PER"
		(layer "F.Cu")
		(at 110.4216 55.0162)
		(property "Reference" "U29"
			(at -1.3968 -2.373079 0)
			(unlocked yes)
			(layer "F.SilkS")
			(effects
				(font
					(size 0.762 0.762)
					(thickness 0.2032)
				)
			)
		)
		(property "Value" "PI3A412ZHE"
			(at 4.684 3.722871 0)
			(unlocked yes)
			(layer "F.SilkS")
			(hide yes)
			(effects
				(font
					(size 0.762 0.762)
					(thickness 0.2032)
				)
			)
		)
		(sheetname "11-M2_RCB_MUX")
		(sheetfile "11-M2_RCB_MUX.kicad_sch")
		(duplicate_pad_numbers_are_jumpers no)
		(fp_line
			(start -1.6764 -1.6764)
			(end -1.20974 -1.6764)
			(stroke
				(width 0.1524)
				(type solid)
			)
			(layer "F.SilkS")
		)
		(fp_line
			(start -1.6764 -1.20974)
			(end -1.6764 -1.6764)
			(stroke
				(width 0.1524)
				(type solid)
			)
			(layer "F.SilkS")
		)
		(fp_line
			(start -1.6764 1.6764)
			(end -1.6764 1.20974)
			(stroke
				(width 0.1524)
				(type solid)
			)
			(layer "F.SilkS")
		)
		(fp_line
			(start -1.6764 1.6764)
			(end -1.20974 1.6764)
			(stroke
				(width 0.1524)
				(type solid)
			)
			(layer "F.SilkS")
		)
		(fp_line
			(start 1.20974 -1.6764)
			(end 1.6764 -1.6764)
			(stroke
				(width 0.1524)
				(type solid)
			)
			(layer "F.SilkS")
		)
		(fp_line
			(start 1.20974 1.6764)
			(end 1.6764 1.6764)
			(stroke
				(width 0.1524)
				(type solid)
			)
			(layer "F.SilkS")
		)
		(fp_line
			(start 1.6764 -1.20974)
			(end 1.6764 -1.6764)
			(stroke
				(width 0.1524)
				(type solid)
			)
			(layer "F.SilkS")
		)
		(fp_line
			(start 1.6764 1.6764)
			(end 1.6764 1.20974)
			(stroke
				(width 0.1524)
				(type solid)
			)
			(layer "F.SilkS")
		)
		(fp_poly
			(pts
				(xy 2.1082 0.0595) (xy 2.3622 0.0595) (xy 2.3622 0.4405) (xy 2.1082 0.4405)
			)
			(stroke
				(width 0)
				(type default)
			)
			(fill yes)
			(layer "F.SilkS")
		)
		(fp_text user "*"
			(at -2.8067 -0.209425 0)
			(unlocked yes)
			(layer "F.SilkS")
			(effects
				(font
					(size 1.27 1.27)
					(thickness 0.0762)
				)
				(justify left bottom)
			)
		)
		(pad "1" smd rect
			(at -1.4478 -0.75 270)
			(size 0.254 0.8128)
			(layers "F.Cu" "F.Mask" "F.Paste")
			(net "RCB_GPS1_TX")
			(solder_mask_margin 0)
			(solder_paste_margin 0)
		)
		(pad "2" smd rect
			(at -1.4478 -0.25 270)
			(size 0.254 0.8128)
			(layers "F.Cu" "F.Mask" "F.Paste")
			(net "DIP_SW_GPS1_SEL")
			(solder_mask_margin 0)
			(solder_paste_margin 0)
		)
		(pad "3" smd rect
			(at -1.4478 0.25 270)
			(size 0.254 0.8128)
			(layers "F.Cu" "F.Mask" "F.Paste")
			(net "M2_GPS1_RX")
			(solder_mask_margin 0)
			(solder_paste_margin 0)
		)
		(pad "4" smd rect
			(at -1.4478 0.75 270)
			(size 0.254 0.8128)
			(layers "F.Cu" "F.Mask" "F.Paste")
			(net "NetR152_1")
			(solder_mask_margin 0)
			(solder_paste_margin 0)
		)
		(pad "5" smd rect
			(at -0.75 1.4478 180)
			(size 0.254 0.8128)
			(layers "F.Cu" "F.Mask" "F.Paste")
			(net "RCB_GPS1_RX")
			(solder_mask_margin 0)
			(solder_paste_margin 0)
		)
		(pad "6" smd rect
			(at -0.25 1.4478 180)
			(size 0.254 0.8128)
			(layers "F.Cu" "F.Mask" "F.Paste")
			(net "GND")
			(solder_mask_margin 0)
			(solder_paste_margin 0)
		)
		(pad "7" smd rect
			(at 0.25 1.4478 180)
			(size 0.254 0.8128)
			(layers "F.Cu" "F.Mask" "F.Paste")
			(net "M2_GPS1_TP1")
			(solder_mask_margin 0)
			(solder_paste_margin 0)
		)
		(pad "8" smd rect
			(at 0.75 1.4478 180)
			(size 0.254 0.8128)
			(layers "F.Cu" "F.Mask" "F.Paste")
			(net "NetR150_1")
			(solder_mask_margin 0)
			(solder_paste_margin 0)
		)
		(pad "9" smd rect
			(at 1.4478 0.75 270)
			(size 0.254 0.8128)
			(layers "F.Cu" "F.Mask" "F.Paste")
			(net "RCB_GPS1_TP1")
			(solder_mask_margin 0)
			(solder_paste_margin 0)
		)
		(pad "10" smd rect
			(at 1.4478 0.25 270)
			(size 0.254 0.8128)
			(layers "F.Cu" "F.Mask" "F.Paste")
			(net "DIP_SW_GPS1_SEL")
			(solder_mask_margin 0)
			(solder_paste_margin 0)
		)
		(pad "11" smd rect
			(at 1.4478 -0.25 270)
			(size 0.254 0.8128)
			(layers "F.Cu" "F.Mask" "F.Paste")
			(net "M2_GPS1_TP2")
			(solder_mask_margin 0)
			(solder_paste_margin 0)
		)
		(pad "12" smd rect
			(at 1.4478 -0.75 270)
			(size 0.254 0.8128)
			(layers "F.Cu" "F.Mask" "F.Paste")
			(net "NetR147_1")
			(solder_mask_margin 0)
			(solder_paste_margin 0)
		)
		(pad "13" smd rect
			(at 0.75 -1.4478 180)
			(size 0.254 0.8128)
			(layers "F.Cu" "F.Mask" "F.Paste")
			(net "RCB_GPS1_TP2")
			(solder_mask_margin 0)
			(solder_paste_margin 0)
		)
		(pad "14" smd rect
			(at 0.25 -1.4478 180)
			(size 0.254 0.8128)
			(layers "F.Cu" "F.Mask" "F.Paste")
			(net "+3.3V")
			(solder_mask_margin 0)
			(solder_paste_margin 0)
		)
		(pad "15" smd rect
			(at -0.25 -1.4478 180)
			(size 0.254 0.8128)
			(layers "F.Cu" "F.Mask" "F.Paste")
			(net "M2_GPS1_TX")
			(solder_mask_margin 0)
			(solder_paste_margin 0)
		)
		(pad "16" smd rect
			(at -0.75 -1.4478 180)
			(size 0.254 0.8128)
			(layers "F.Cu" "F.Mask" "F.Paste")
			(net "NetR144_1")
			(solder_mask_margin 0)
			(solder_paste_margin 0)
		)
		(pad "17" smd rect
			(at 0 0)
			(size 1.8034 1.8034)
			(layers "F.Cu" "F.Mask" "F.Paste")
			(net "GND")
			(solder_mask_margin 0)
			(solder_paste_margin 0)
		)
	)
)
